(kicad_pcb
	(version 20241229)
	(generator "pcbnew")
	(generator_version "9.0")
	(general
		(thickness 1.61)
		(legacy_teardrops no)
	)
	(paper "A3")
	(title_block
		(title "SO-DIMM DDR5 Tester")
		(date "2025-11-26")
		(rev "1.3.0")
		(comment 9 "footprints 607-612 of 627")
	)
	(layers
		(0 "F.Cu" signal)
		(4 "In1.Cu" power)
		(6 "In2.Cu" mixed)
		(8 "In3.Cu" power)
		(10 "In4.Cu" mixed)
		(12 "In5.Cu" power)
		(14 "In6.Cu" mixed)
		(16 "In7.Cu" power)
		(18 "In8.Cu" power)
		(20 "In9.Cu" mixed)
		(22 "In10.Cu" power)
		(2 "B.Cu" signal)
		(9 "F.Adhes" user "F.Adhesive")
		(11 "B.Adhes" user "B.Adhesive")
		(13 "F.Paste" user)
		(15 "B.Paste" user)
		(5 "F.SilkS" user "F.Silkscreen")
		(7 "B.SilkS" user "B.Silkscreen")
		(1 "F.Mask" user)
		(3 "B.Mask" user)
		(17 "Dwgs.User" user "User.Drawings")
		(19 "Cmts.User" user "User.Comments")
		(21 "Eco1.User" user "User.Eco1")
		(23 "Eco2.User" user "User.Eco2")
		(25 "Edge.Cuts" user)
		(27 "Margin" user)
		(31 "F.CrtYd" user "F.Courtyard")
		(29 "B.CrtYd" user "B.Courtyard")
		(35 "F.Fab" user)
		(33 "B.Fab" user)
	)
	(footprint "antmicro-footprints:C_0402_1005Metric"
		(layer "B.Cu")
		(at 138.870501 172.296)
		(descr "Capacitor SMD 0402 (1005 Metric), square (rectangular) end terminal, IPC_7351 nominal, (Body size source: IPC-SM-782 page 76, https://www.pcb-3d.com/wordpress/wp-content/uploads/ipc-sm-782a_amendment_1_and_2.pdf)")
		(tags "capacitor 0402")
		(property "Reference" "C61"
			(at 0 1.17 180)
			(layer "B.SilkS")
			(hide yes)
			(effects
				(font
					(size 0.7 0.7)
					(thickness 0.15)
				)
				(justify left bottom mirror)
			)
		)
		(property "Value" "C_100n_0402"
			(at 0 -1.169 180)
			(layer "B.Fab")
			(effects
				(font
					(size 0.7 0.7)
					(thickness 0.15)
				)
				(justify left bottom mirror)
			)
		)
		(property "Datasheet" "https://www.murata.com/products/productdetail?partno=GRM155R61H104KE14%23"
			(at 0 0 0)
			(layer "F.Fab")
			(hide yes)
			(effects
				(font
					(size 1.27 1.27)
					(thickness 0.15)
				)
			)
		)
		(property "Author" "Antmicro"
			(at 0 0 0)
			(layer "B.Fab")
			(hide yes)
			(effects
				(font
					(size 1 1)
					(thickness 0.15)
				)
				(justify mirror)
			)
		)
		(property "Dielectric" "X5R"
			(at 0 0 0)
			(layer "B.Fab")
			(hide yes)
			(effects
				(font
					(size 1 1)
					(thickness 0.15)
				)
				(justify mirror)
			)
		)
		(property "License" "Apache-2.0"
			(at 0 0 0)
			(layer "B.Fab")
			(hide yes)
			(effects
				(font
					(size 1 1)
					(thickness 0.15)
				)
				(justify mirror)
			)
		)
		(property "MPN" "GRM155R61H104KE14D"
			(at 0 0 0)
			(layer "B.Fab")
			(hide yes)
			(effects
				(font
					(size 1 1)
					(thickness 0.15)
				)
				(justify mirror)
			)
		)
		(property "Manufacturer" "Murata"
			(at 0 0 0)
			(layer "B.Fab")
			(hide yes)
			(effects
				(font
					(size 1 1)
					(thickness 0.15)
				)
				(justify mirror)
			)
		)
		(property "Val" "100n"
			(at 0 0 0)
			(layer "B.Fab")
			(hide yes)
			(effects
				(font
					(size 1 1)
					(thickness 0.15)
				)
				(justify mirror)
			)
		)
		(property "Voltage" "50V"
			(at 0 0 0)
			(layer "B.Fab")
			(hide yes)
			(effects
				(font
					(size 1 1)
					(thickness 0.15)
				)
				(justify mirror)
			)
		)
		(sheetname "/FPGA power/")
		(sheetfile "fpga-power.kicad_sch")
		(attr smd)
		(fp_rect
			(start -0.9656 0.4572)
			(end 0.9652 -0.4828)
			(stroke
				(width 0.05)
				(type solid)
			)
			(fill no)
			(layer "B.CrtYd")
		)
		(fp_line
			(start -0.5 -0.248)
			(end -0.5 0.25)
			(stroke
				(width 0.15)
				(type solid)
			)
			(layer "B.Fab")
		)
		(fp_line
			(start -0.5 0.25)
			(end 0.498 0.25)
			(stroke
				(width 0.15)
				(type solid)
			)
			(layer "B.Fab")
		)
		(fp_line
			(start 0.498 -0.248)
			(end -0.5 -0.248)
			(stroke
				(width 0.15)
				(type solid)
			)
			(layer "B.Fab")
		)
		(fp_line
			(start 0.498 0.25)
			(end 0.498 -0.248)
			(stroke
				(width 0.15)
				(type solid)
			)
			(layer "B.Fab")
		)
		(pad "1" smd roundrect
			(at -0.5 0 270)
			(size 0.6 0.6)
			(layers "B.Cu" "B.Mask" "B.Paste")
			(roundrect_rratio 0.25)
			(net 1 "GND")
			(pintype "passive")
		)
		(pad "2" smd roundrect
			(at 0.498 0)
			(size 0.6 0.6)
			(layers "B.Cu" "B.Mask" "B.Paste")
			(roundrect_rratio 0.25)
			(net 227 "+1V0")
			(pintype "passive")
		)
	)
	(footprint "antmicro-footprints:C_0402_1005Metric"
		(layer "B.Cu")
		(at 132.05 142.4 -90)
		(descr "Capacitor SMD 0402")
		(tags "capacitor SMD 0402")
		(property "Reference" "C10"
			(at 0 0.699 90)
			(layer "B.SilkS")
			(hide yes)
			(effects
				(font
					(size 0.7 0.7)
					(thickness 0.15)
				)
				(justify left bottom mirror)
			)
		)
		(property "Value" "C_100n_0402"
			(at -1.022927 -2.155213 90)
			(layer "B.Fab")
			(effects
				(font
					(size 0.7 0.7)
					(thickness 0.15)
				)
				(justify left bottom mirror)
			)
		)
		(property "Datasheet" "https://www.murata.com/products/productdetail?partno=GRM155R61H104KE14%23"
			(at 0 0 270)
			(layer "F.Fab")
			(hide yes)
			(effects
				(font
					(size 1.27 1.27)
					(thickness 0.15)
				)
			)
		)
		(property "Author" "Antmicro"
			(at -10.35 274.45 0)
			(layer "B.Fab")
			(hide yes)
			(effects
				(font
					(size 1 1)
					(thickness 0.15)
				)
				(justify mirror)
			)
		)
		(property "Dielectric" "X5R"
			(at -10.35 274.45 0)
			(layer "B.Fab")
			(hide yes)
			(effects
				(font
					(size 1 1)
					(thickness 0.15)
				)
				(justify mirror)
			)
		)
		(property "License" "Apache-2.0"
			(at -10.35 274.45 0)
			(layer "B.Fab")
			(hide yes)
			(effects
				(font
					(size 1 1)
					(thickness 0.15)
				)
				(justify mirror)
			)
		)
		(property "MPN" "GRM155R61H104KE14D"
			(at -10.35 274.45 0)
			(layer "B.Fab")
			(hide yes)
			(effects
				(font
					(size 1 1)
					(thickness 0.15)
				)
				(justify mirror)
			)
		)
		(property "Manufacturer" "Murata"
			(at -10.35 274.45 0)
			(layer "B.Fab")
			(hide yes)
			(effects
				(font
					(size 1 1)
					(thickness 0.15)
				)
				(justify mirror)
			)
		)
		(property "Val" "100n"
			(at -10.35 274.45 0)
			(layer "B.Fab")
			(hide yes)
			(effects
				(font
					(size 1 1)
					(thickness 0.15)
				)
				(justify mirror)
			)
		)
		(property "Voltage" "50V"
			(at -10.35 274.45 0)
			(layer "B.Fab")
			(hide yes)
			(effects
				(font
					(size 1 1)
					(thickness 0.15)
				)
				(justify mirror)
			)
		)
		(sheetname "/DDR5 SODIMM/")
		(sheetfile "ddr5-sodimm.kicad_sch")
		(attr smd)
		(fp_rect
			(start -0.9659 0.481258)
			(end 0.9649 -0.458742)
			(stroke
				(width 0.05)
				(type solid)
			)
			(fill no)
			(layer "B.CrtYd")
		)
		(fp_line
			(start -0.499 0.25)
			(end 0.499 0.25)
			(stroke
				(width 0.15)
				(type solid)
			)
			(layer "B.Fab")
		)
		(fp_line
			(start 0.499 0.25)
			(end 0.499 -0.248)
			(stroke
				(width 0.15)
				(type solid)
			)
			(layer "B.Fab")
		)
		(fp_line
			(start -0.499 -0.248)
			(end -0.499 0.25)
			(stroke
				(width 0.15)
				(type solid)
			)
			(layer "B.Fab")
		)
		(fp_line
			(start 0.499 -0.248)
			(end -0.499 -0.248)
			(stroke
				(width 0.15)
				(type solid)
			)
			(layer "B.Fab")
		)
		(pad "1" smd roundrect
			(at -0.484 0 270)
			(size 0.59 0.64)
			(layers "B.Cu" "B.Mask" "B.Paste")
			(roundrect_rratio 0.25)
			(net 1 "GND")
			(pintype "passive")
		)
		(pad "2" smd roundrect
			(at 0.484 0 270)
			(size 0.59 0.64)
			(layers "B.Cu" "B.Mask" "B.Paste")
			(roundrect_rratio 0.25)
			(net 206 "+1V1")
			(pintype "passive")
		)
	)
	(footprint "antmicro-footprints:C_0402_1005Metric"
		(layer "B.Cu")
		(at 144.875001 176.3025)
		(descr "Capacitor SMD 0402 (1005 Metric), square (rectangular) end terminal, IPC_7351 nominal, (Body size source: IPC-SM-782 page 76, https://www.pcb-3d.com/wordpress/wp-content/uploads/ipc-sm-782a_amendment_1_and_2.pdf)")
		(tags "capacitor 0402")
		(property "Reference" "C42"
			(at 0 1.17 180)
			(layer "B.SilkS")
			(hide yes)
			(effects
				(font
					(size 0.7 0.7)
					(thickness 0.15)
				)
				(justify left bottom mirror)
			)
		)
		(property "Value" "C_100n_0402"
			(at 0 -1.169 180)
			(layer "B.Fab")
			(effects
				(font
					(size 0.7 0.7)
					(thickness 0.15)
				)
				(justify left bottom mirror)
			)
		)
		(property "Datasheet" "https://www.murata.com/products/productdetail?partno=GRM155R61H104KE14%23"
			(at 0 0 0)
			(layer "F.Fab")
			(hide yes)
			(effects
				(font
					(size 1.27 1.27)
					(thickness 0.15)
				)
			)
		)
		(property "Author" "Antmicro"
			(at 0 0 0)
			(layer "B.Fab")
			(hide yes)
			(effects
				(font
					(size 1 1)
					(thickness 0.15)
				)
				(justify mirror)
			)
		)
		(property "Dielectric" "X5R"
			(at 0 0 0)
			(layer "B.Fab")
			(hide yes)
			(effects
				(font
					(size 1 1)
					(thickness 0.15)
				)
				(justify mirror)
			)
		)
		(property "License" "Apache-2.0"
			(at 0 0 0)
			(layer "B.Fab")
			(hide yes)
			(effects
				(font
					(size 1 1)
					(thickness 0.15)
				)
				(justify mirror)
			)
		)
		(property "MPN" "GRM155R61H104KE14D"
			(at 0 0 0)
			(layer "B.Fab")
			(hide yes)
			(effects
				(font
					(size 1 1)
					(thickness 0.15)
				)
				(justify mirror)
			)
		)
		(property "Manufacturer" "Murata"
			(at 0 0 0)
			(layer "B.Fab")
			(hide yes)
			(effects
				(font
					(size 1 1)
					(thickness 0.15)
				)
				(justify mirror)
			)
		)
		(property "Val" "100n"
			(at 0 0 0)
			(layer "B.Fab")
			(hide yes)
			(effects
				(font
					(size 1 1)
					(thickness 0.15)
				)
				(justify mirror)
			)
		)
		(property "Voltage" "50V"
			(at 0 0 0)
			(layer "B.Fab")
			(hide yes)
			(effects
				(font
					(size 1 1)
					(thickness 0.15)
				)
				(justify mirror)
			)
		)
		(sheetname "/FPGA power/")
		(sheetfile "fpga-power.kicad_sch")
		(attr smd)
		(fp_rect
			(start -0.9656 0.4572)
			(end 0.9652 -0.4828)
			(stroke
				(width 0.05)
				(type solid)
			)
			(fill no)
			(layer "B.CrtYd")
		)
		(fp_line
			(start -0.5 -0.248)
			(end -0.5 0.25)
			(stroke
				(width 0.15)
				(type solid)
			)
			(layer "B.Fab")
		)
		(fp_line
			(start -0.5 0.25)
			(end 0.498 0.25)
			(stroke
				(width 0.15)
				(type solid)
			)
			(layer "B.Fab")
		)
		(fp_line
			(start 0.498 -0.248)
			(end -0.5 -0.248)
			(stroke
				(width 0.15)
				(type solid)
			)
			(layer "B.Fab")
		)
		(fp_line
			(start 0.498 0.25)
			(end 0.498 -0.248)
			(stroke
				(width 0.15)
				(type solid)
			)
			(layer "B.Fab")
		)
		(pad "1" smd roundrect
			(at -0.5 0 270)
			(size 0.6 0.6)
			(layers "B.Cu" "B.Mask" "B.Paste")
			(roundrect_rratio 0.25)
			(net 1 "GND")
			(pintype "passive")
		)
		(pad "2" smd roundrect
			(at 0.498 0)
			(size 0.6 0.6)
			(layers "B.Cu" "B.Mask" "B.Paste")
			(roundrect_rratio 0.25)
			(net 227 "+1V0")
			(pintype "passive")
		)
	)
	(footprint "antmicro-footprints:TP_SMD_1mm"
		(layer "B.Cu")
		(at 190.5 161.7 180)
		(property "Reference" "TP61"
			(at -3.2 -0.25 0)
			(layer "B.SilkS")
			(effects
				(font
					(size 0.7 0.7)
					(thickness 0.15)
				)
				(justify left bottom mirror)
			)
		)
		(property "Value" "TP_1mm_SMD"
			(at 0 -1.4 0)
			(layer "B.Fab")
			(effects
				(font
					(size 0.7 0.7)
					(thickness 0.15)
				)
				(justify left bottom mirror)
			)
		)
		(property "MPN" ""
			(at 0 0 0)
			(unlocked yes)
			(layer "B.Fab")
			(hide yes)
			(effects
				(font
					(size 1 1)
					(thickness 0.15)
				)
				(justify mirror)
			)
		)
		(property "Manufacturer" ""
			(at 0 0 0)
			(unlocked yes)
			(layer "B.Fab")
			(hide yes)
			(effects
				(font
					(size 1 1)
					(thickness 0.15)
				)
				(justify mirror)
			)
		)
		(property "Author" "Antmicro"
			(at 0 0 0)
			(unlocked yes)
			(layer "B.Fab")
			(hide yes)
			(effects
				(font
					(size 1 1)
					(thickness 0.15)
				)
				(justify mirror)
			)
		)
		(property "License" "Apache-2.0"
			(at 0 0 0)
			(unlocked yes)
			(layer "B.Fab")
			(hide yes)
			(effects
				(font
					(size 1 1)
					(thickness 0.15)
				)
				(justify mirror)
			)
		)
		(sheetname "/Supply/")
		(sheetfile "supply.kicad_sch")
		(attr exclude_from_pos_files)
		(fp_circle
			(center 0 0)
			(end 0.6 0)
			(stroke
				(width 0.05)
				(type default)
			)
			(fill no)
			(layer "B.CrtYd")
		)
		(fp_text user "${REFERENCE}"
			(at -0.5 -2.8 0)
			(layer "B.Fab")
			(effects
				(font
					(size 0.7 0.7)
					(thickness 0.15)
				)
				(justify left bottom mirror)
			)
		)
		(fp_text user "License: Apache-2.0"
			(at -0.5 -5.2 0)
			(layer "B.Fab")
			(effects
				(font
					(size 0.7 0.7)
					(thickness 0.15)
				)
				(justify left bottom mirror)
			)
		)
		(fp_text user "Author: Antmicro"
			(at -0.5 -4 0)
			(layer "B.Fab")
			(effects
				(font
					(size 0.7 0.7)
					(thickness 0.15)
				)
				(justify left bottom mirror)
			)
		)
		(pad "1" smd circle
			(at 0 0 180)
			(size 1 1)
			(layers "B.Cu" "B.Mask")
			(net 60 "/Supply/5V_local")
			(pinfunction "1")
			(pintype "passive")
		)
	)
	(footprint "antmicro-footprints:R_0402_1005Metric"
		(layer "B.Cu")
		(at 202.925 182.4 90)
		(descr "Resistor SMD 0402")
		(tags "resistor SMD 0402")
		(property "Reference" "R163"
			(at 3.9 0.325 270)
			(layer "B.SilkS")
			(effects
				(font
					(size 0.7 0.7)
					(thickness 0.15)
				)
				(justify left bottom mirror)
			)
		)
		(property "Value" "R_0R_0402"
			(at -1.011843 -1.772047 270)
			(layer "B.Fab")
			(effects
				(font
					(size 0.7 0.7)
					(thickness 0.15)
				)
				(justify left bottom mirror)
			)
		)
		(property "Datasheet" "https://industrial.panasonic.com/cdbs/www-data/pdf/RDA0000/AOA0000C301.pdf"
			(at 0 0 90)
			(layer "F.Fab")
			(hide yes)
			(effects
				(font
					(size 1.27 1.27)
					(thickness 0.15)
				)
			)
		)
		(property "Author" "Antmicro"
			(at 385.325 -20.525 0)
			(layer "B.Fab")
			(hide yes)
			(effects
				(font
					(size 1 1)
					(thickness 0.15)
				)
				(justify mirror)
			)
		)
		(property "Current" "1A"
			(at 385.325 -20.525 0)
			(layer "B.Fab")
			(hide yes)
			(effects
				(font
					(size 1 1)
					(thickness 0.15)
				)
				(justify mirror)
			)
		)
		(property "License" "Apache-2.0"
			(at 385.325 -20.525 0)
			(layer "B.Fab")
			(hide yes)
			(effects
				(font
					(size 1 1)
					(thickness 0.15)
				)
				(justify mirror)
			)
		)
		(property "MPN" "ERJ2GE0R00X"
			(at 385.325 -20.525 0)
			(layer "B.Fab")
			(hide yes)
			(effects
				(font
					(size 1 1)
					(thickness 0.15)
				)
				(justify mirror)
			)
		)
		(property "Manufacturer" "Panasonic"
			(at 385.325 -20.525 0)
			(layer "B.Fab")
			(hide yes)
			(effects
				(font
					(size 1 1)
					(thickness 0.15)
				)
				(justify mirror)
			)
		)
		(property "Tolerance" ""
			(at 385.325 -20.525 0)
			(layer "B.Fab")
			(hide yes)
			(effects
				(font
					(size 1 1)
					(thickness 0.15)
				)
				(justify mirror)
			)
		)
		(property "Val" "0R"
			(at 385.325 -20.525 0)
			(layer "B.Fab")
			(hide yes)
			(effects
				(font
					(size 1 1)
					(thickness 0.15)
				)
				(justify mirror)
			)
		)
		(sheetname "/Supply/")
		(sheetfile "supply.kicad_sch")
		(attr exclude_from_pos_files exclude_from_bom dnp)
		(fp_rect
			(start -0.93 0.47)
			(end 0.93 -0.47)
			(stroke
				(width 0.05)
				(type solid)
			)
			(fill no)
			(layer "B.CrtYd")
		)
		(fp_rect
			(start -0.5 0.25)
			(end 0.5 -0.25)
			(stroke
				(width 0.15)
				(type solid)
			)
			(fill no)
			(layer "B.Fab")
		)
		(pad "1" smd roundrect
			(at -0.485 0 90)
			(size 0.59 0.64)
			(layers "B.Cu" "B.Mask" "B.Paste")
			(roundrect_rratio 0.25)
			(net 1 "GND")
			(pintype "passive")
		)
		(pad "2" smd roundrect
			(at 0.485 0 90)
			(size 0.59 0.64)
			(layers "B.Cu" "B.Mask" "B.Paste")
			(roundrect_rratio 0.25)
			(net 216 "/Supply/FB3")
			(pintype "passive")
		)
	)
	(footprint "antmicro-footprints:C_0402_1005Metric"
		(layer "B.Cu")
		(at 145.375501 169.801 90)
		(descr "Capacitor SMD 0402 (1005 Metric), square (rectangular) end terminal, IPC_7351 nominal, (Body size source: IPC-SM-782 page 76, https://www.pcb-3d.com/wordpress/wp-content/uploads/ipc-sm-782a_amendment_1_and_2.pdf)")
		(tags "capacitor 0402")
		(property "Reference" "C82"
			(at 0 1.17 270)
			(layer "B.SilkS")
			(hide yes)
			(effects
				(font
					(size 0.7 0.7)
					(thickness 0.15)
				)
				(justify left bottom mirror)
			)
		)
		(property "Value" "C_100n_0402"
			(at 0 -1.169 270)
			(layer "B.Fab")
			(effects
				(font
					(size 0.7 0.7)
					(thickness 0.15)
				)
				(justify left bottom mirror)
			)
		)
		(property "Datasheet" "https://www.murata.com/products/productdetail?partno=GRM155R61H104KE14%23"
			(at 0 0 90)
			(layer "F.Fab")
			(hide yes)
			(effects
				(font
					(size 1.27 1.27)
					(thickness 0.15)
				)
			)
		)
		(property "Author" "Antmicro"
			(at 315.176501 24.425499 0)
			(layer "B.Fab")
			(hide yes)
			(effects
				(font
					(size 1 1)
					(thickness 0.15)
				)
				(justify mirror)
			)
		)
		(property "Dielectric" "X5R"
			(at 315.176501 24.425499 0)
			(layer "B.Fab")
			(hide yes)
			(effects
				(font
					(size 1 1)
					(thickness 0.15)
				)
				(justify mirror)
			)
		)
		(property "License" "Apache-2.0"
			(at 315.176501 24.425499 0)
			(layer "B.Fab")
			(hide yes)
			(effects
				(font
					(size 1 1)
					(thickness 0.15)
				)
				(justify mirror)
			)
		)
		(property "MPN" "GRM155R61H104KE14D"
			(at 315.176501 24.425499 0)
			(layer "B.Fab")
			(hide yes)
			(effects
				(font
					(size 1 1)
					(thickness 0.15)
				)
				(justify mirror)
			)
		)
		(property "Manufacturer" "Murata"
			(at 315.176501 24.425499 0)
			(layer "B.Fab")
			(hide yes)
			(effects
				(font
					(size 1 1)
					(thickness 0.15)
				)
				(justify mirror)
			)
		)
		(property "Val" "100n"
			(at 315.176501 24.425499 0)
			(layer "B.Fab")
			(hide yes)
			(effects
				(font
					(size 1 1)
					(thickness 0.15)
				)
				(justify mirror)
			)
		)
		(property "Voltage" "50V"
			(at 315.176501 24.425499 0)
			(layer "B.Fab")
			(hide yes)
			(effects
				(font
					(size 1 1)
					(thickness 0.15)
				)
				(justify mirror)
			)
		)
		(sheetname "/FPGA power/")
		(sheetfile "fpga-power.kicad_sch")
		(attr smd)
		(fp_rect
			(start -0.9656 0.4572)
			(end 0.9652 -0.4828)
			(stroke
				(width 0.05)
				(type solid)
			)
			(fill no)
			(layer "B.CrtYd")
		)
		(fp_line
			(start 0.498 -0.248)
			(end -0.5 -0.248)
			(stroke
				(width 0.15)
				(type solid)
			)
			(layer "B.Fab")
		)
		(fp_line
			(start -0.5 -0.248)
			(end -0.5 0.25)
			(stroke
				(width 0.15)
				(type solid)
			)
			(layer "B.Fab")
		)
		(fp_line
			(start 0.498 0.25)
			(end 0.498 -0.248)
			(stroke
				(width 0.15)
				(type solid)
			)
			(layer "B.Fab")
		)
		(fp_line
			(start -0.5 0.25)
			(end 0.498 0.25)
			(stroke
				(width 0.15)
				(type solid)
			)
			(layer "B.Fab")
		)
		(pad "1" smd roundrect
			(at -0.5 0)
			(size 0.6 0.6)
			(layers "B.Cu" "B.Mask" "B.Paste")
			(roundrect_rratio 0.25)
			(net 1 "GND")
			(pintype "passive")
		)
		(pad "2" smd roundrect
			(at 0.498 0 90)
			(size 0.6 0.6)
			(layers "B.Cu" "B.Mask" "B.Paste")
			(roundrect_rratio 0.25)
			(net 206 "+1V1")
			(pintype "passive")
		)
	)
)
